(kicad_pcb
	(version 20260206)
	(generator "pcbnew")
	(generator_version "10.0")
	(general
		(thickness 1.59074)
		(legacy_teardrops no)
	)
	(paper "A4")
	(title_block
		(title "osc-sa45 — FAB_SA45_DaughterCard.PcbDoc")
		(comment 1 "Time Appliance Project (Time Card) / footprints 39-44 of 44")
	)
	(layers
		(0 "F.Cu" signal "L01-Top Layer")
		(4 "In1.Cu" signal "L02-Inner Layer")
		(6 "In2.Cu" signal "L03-Inner Layer")
		(2 "B.Cu" signal "L04-Bottom Layer")
		(9 "F.Adhes" user "F.Adhesive")
		(11 "B.Adhes" user "B.Adhesive")
		(13 "F.Paste" user "Top Paste")
		(15 "B.Paste" user "Bottom Paste")
		(5 "F.SilkS" user "Top Overlay")
		(7 "B.SilkS" user "Bottom Overlay")
		(1 "F.Mask" user "Top Solder")
		(3 "B.Mask" user "Bottom Solder")
		(17 "Dwgs.User" user "User.Drawings")
		(19 "Cmts.User" user "User.Comments")
		(21 "Eco1.User" user "User.Eco1")
		(23 "Eco2.User" user "User.Eco2")
		(25 "Edge.Cuts" user)
		(27 "Margin" user)
		(31 "F.CrtYd" user "Top Courtyard")
		(29 "B.CrtYd" user "Bottom Courtyard")
		(35 "F.Fab" user "Top Component Outline")
		(33 "B.Fab" user "Bottom Component Outline 2")
	)
	(footprint "Vault:CAPC1005X055N"
		(layer "B.Cu")
		(at 145.276105 110.553605)
		(property "Reference" "C6"
			(at -2.1 -0.12655 0)
			(unlocked yes)
			(layer "B.SilkS")
			(effects
				(font
					(face "Arial")
					(size 0.63 0.63)
					(thickness 0.254)
				)
				(justify mirror)
			)
		)
		(property "Value" "Murata_GRM155R61H104KE14D"
			(at -28.015845 -0.3605 0)
			(unlocked yes)
			(layer "B.SilkS")
			(hide yes)
			(effects
				(font
					(face "Arial")
					(size 0.63 0.63)
					(thickness 0.254)
				)
				(justify mirror)
			)
		)
		(sheetname "SCH_SA45_DaughterCard")
		(sheetfile "SCH_SA45_DaughterCard.kicad_sch")
		(duplicate_pad_numbers_are_jumpers no)
		(fp_line
			(start -0.95 -0.5)
			(end 0.95 -0.5)
			(stroke
				(width 0.1)
				(type solid)
			)
			(layer "B.CrtYd")
		)
		(fp_line
			(start -0.95 0.5)
			(end -0.95 -0.5)
			(stroke
				(width 0.1)
				(type solid)
			)
			(layer "B.CrtYd")
		)
		(fp_line
			(start -0.95 0.5)
			(end 0.95 0.5)
			(stroke
				(width 0.1)
				(type solid)
			)
			(layer "B.CrtYd")
		)
		(fp_line
			(start 0.95 0.5)
			(end 0.95 -0.5)
			(stroke
				(width 0.1)
				(type solid)
			)
			(layer "B.CrtYd")
		)
		(fp_line
			(start -0.5 -0.25)
			(end 0.5 -0.25)
			(stroke
				(width 0.05)
				(type solid)
			)
			(layer "B.Fab")
		)
		(fp_line
			(start -0.5 0.25)
			(end -0.5 -0.25)
			(stroke
				(width 0.05)
				(type solid)
			)
			(layer "B.Fab")
		)
		(fp_line
			(start -0.5 0.25)
			(end 0.5 0.25)
			(stroke
				(width 0.05)
				(type solid)
			)
			(layer "B.Fab")
		)
		(fp_line
			(start 0.5 0.25)
			(end 0.5 -0.25)
			(stroke
				(width 0.05)
				(type solid)
			)
			(layer "B.Fab")
		)
		(fp_text_box "${REFERENCE}"
			(start 1.09006 0.20729)
			(end -1.09002 -0.20729)
			(margins 0 0 0 0)
			(angle 180)
			(layer "B.Fab")
			(effects
				(font
					(face "Arial")
					(size 0.315 0.315)
					(thickness 0.254)
				)
				(justify top mirror)
			)
			(border no)
			(stroke
				(width 0.1)
				(type default)
			)
			(knockout no)
		)
		(pad "1" smd rect
			(at -0.46 0)
			(size 0.6 0.62)
			(layers "B.Cu" "B.Mask" "B.Paste")
			(net "+5V")
			(solder_mask_margin 0.05)
			(solder_paste_margin 0)
		)
		(pad "2" smd rect
			(at 0.46 0)
			(size 0.6 0.62)
			(layers "B.Cu" "B.Mask" "B.Paste")
			(net "GND")
			(solder_mask_margin 0.05)
			(solder_paste_margin 0)
		)
	)
	(footprint "FAB_SA45_DaughterCard:Keystone_4871"
		(locked yes)
		(layer "B.Cu")
		(at 132.561105 86.743605 180)
		(property "Reference" "J6"
			(at 0.106965 -3.74429 0)
			(unlocked yes)
			(layer "B.SilkS")
			(effects
				(font
					(face "Arial")
					(size 0.63 0.63)
					(thickness 0.254)
				)
				(justify mirror)
			)
		)
		(property "Value" "Keystone_4871"
			(at 6.3343 -5.019802 0)
			(unlocked yes)
			(layer "B.SilkS")
			(hide yes)
			(effects
				(font
					(size 1.524 1.524)
					(thickness 0.254)
				)
				(justify mirror)
			)
		)
		(sheetname "SCH_SA45_DaughterCard")
		(sheetfile "SCH_SA45_DaughterCard.kicad_sch")
		(duplicate_pad_numbers_are_jumpers no)
		(fp_line
			(start 3.4 3.4)
			(end -3.4 3.4)
			(stroke
				(width 0.1)
				(type solid)
			)
			(layer "B.CrtYd")
		)
		(fp_line
			(start 3.4 -3.4)
			(end 3.4 3.4)
			(stroke
				(width 0.1)
				(type solid)
			)
			(layer "B.CrtYd")
		)
		(fp_line
			(start 3.4 -3.4)
			(end -3.4 -3.4)
			(stroke
				(width 0.1)
				(type solid)
			)
			(layer "B.CrtYd")
		)
		(fp_line
			(start -3.4 -0.8)
			(end -3.4 3.4)
			(stroke
				(width 0.1)
				(type solid)
			)
			(layer "B.CrtYd")
		)
		(fp_line
			(start -3.4 -3.4)
			(end -3.4 -0.8)
			(stroke
				(width 0.1)
				(type solid)
			)
			(layer "B.CrtYd")
		)
		(fp_text user ""
			(at 0.367795 0.63446 360)
			(unlocked yes)
			(layer "B.Fab")
			(effects
				(font
					(face "Arial")
					(size 0.63 0.63)
					(thickness 0.254)
				)
				(justify mirror)
			)
		)
		(fp_text user "${REFERENCE}"
			(at -0.001845 0.19946 360)
			(unlocked yes)
			(layer "B.Fab")
			(effects
				(font
					(face "Arial")
					(size 0.63 0.63)
					(thickness 0.254)
				)
				(justify mirror)
			)
		)
		(pad "Hole" thru_hole circle
			(at 0 0 180)
			(size 0 0)
			(drill 3.7)
			(layers "*.Cu" "*.Mask")
			(remove_unused_layers no)
			(thermal_bridge_angle 90)
		)
		(pad "MT" smd circle
			(at 0 0 180)
			(size 6.2 6.2)
			(layers "B.Cu" "B.Mask" "B.Paste")
			(solder_mask_margin 0.05)
			(thermal_bridge_angle 90)
		)
	)
	(footprint "Vault:CAPC0603X033N"
		(layer "B.Cu")
		(at 144.786105 103.053605 180)
		(property "Reference" "C9"
			(at -0.33 2.60155 0)
			(unlocked yes)
			(layer "B.SilkS")
			(effects
				(font
					(face "Arial")
					(size 0.63 0.63)
					(thickness 0.254)
				)
				(justify mirror)
			)
		)
		(property "Value" "Murata_GRM033R61A332KA01D"
			(at 18.677945 -13.23094 0)
			(unlocked yes)
			(layer "B.SilkS")
			(hide yes)
			(effects
				(font
					(face "Arial")
					(size 0.63 0.63)
					(thickness 0.254)
				)
				(justify mirror)
			)
		)
		(sheetname "SCH_SA45_DaughterCard")
		(sheetfile "SCH_SA45_DaughterCard.kicad_sch")
		(duplicate_pad_numbers_are_jumpers no)
		(fp_line
			(start 0.75 0.4)
			(end -0.75 0.4)
			(stroke
				(width 0.1)
				(type solid)
			)
			(layer "B.CrtYd")
		)
		(fp_line
			(start 0.75 -0.4)
			(end 0.75 0.4)
			(stroke
				(width 0.1)
				(type solid)
			)
			(layer "B.CrtYd")
		)
		(fp_line
			(start 0.75 -0.4)
			(end -0.75 -0.4)
			(stroke
				(width 0.1)
				(type solid)
			)
			(layer "B.CrtYd")
		)
		(fp_line
			(start -0.75 -0.4)
			(end -0.75 0.4)
			(stroke
				(width 0.1)
				(type solid)
			)
			(layer "B.CrtYd")
		)
		(fp_line
			(start 0.3 0.15)
			(end -0.3 0.15)
			(stroke
				(width 0.05)
				(type solid)
			)
			(layer "B.Fab")
		)
		(fp_line
			(start 0.3 -0.15)
			(end 0.3 0.15)
			(stroke
				(width 0.05)
				(type solid)
			)
			(layer "B.Fab")
		)
		(fp_line
			(start 0.3 -0.15)
			(end -0.3 -0.15)
			(stroke
				(width 0.05)
				(type solid)
			)
			(layer "B.Fab")
		)
		(fp_line
			(start -0.3 -0.15)
			(end -0.3 0.15)
			(stroke
				(width 0.05)
				(type solid)
			)
			(layer "B.Fab")
		)
		(fp_text_box "${REFERENCE}"
			(start 1.09004 0.20727)
			(end -1.09004 -0.20726)
			(margins 0 0 0 0)
			(angle -180)
			(layer "B.Fab")
			(effects
				(font
					(face "Arial")
					(size 0.315 0.315)
					(thickness 0.254)
				)
				(justify top mirror)
			)
			(border no)
			(stroke
				(width 0.1)
				(type default)
			)
			(knockout no)
		)
		(pad "1" smd rect
			(at -0.33 0 180)
			(size 0.46 0.42)
			(layers "B.Cu" "B.Mask" "B.Paste")
			(net "NetC9_1")
			(solder_mask_margin 0.05)
			(solder_paste_margin 0)
		)
		(pad "2" smd rect
			(at 0.33 0 180)
			(size 0.46 0.42)
			(layers "B.Cu" "B.Mask" "B.Paste")
			(net "GND")
			(solder_mask_margin 0.05)
			(solder_paste_margin 0)
		)
	)
	(footprint "Vault:CAPC1005X061N"
		(layer "B.Cu")
		(at 166.471105 115.403605)
		(property "Reference" "C1"
			(at 1.779995 -0.12655 0)
			(unlocked yes)
			(layer "B.SilkS")
			(effects
				(font
					(face "Arial")
					(size 0.63 0.63)
					(thickness 0.254)
				)
				(justify mirror)
			)
		)
		(property "Value" "Murata_GRM155R6YA105KE11D"
			(at -9.64079 5.13679 0)
			(unlocked yes)
			(layer "B.SilkS")
			(hide yes)
			(effects
				(font
					(face "Arial")
					(size 0.63 0.63)
					(thickness 0.254)
				)
				(justify mirror)
			)
		)
		(sheetname "SCH_SA45_DaughterCard")
		(sheetfile "SCH_SA45_DaughterCard.kicad_sch")
		(duplicate_pad_numbers_are_jumpers no)
		(fp_line
			(start -0.95 -0.5)
			(end 0.95 -0.5)
			(stroke
				(width 0.1)
				(type solid)
			)
			(layer "B.CrtYd")
		)
		(fp_line
			(start -0.95 0.5)
			(end -0.95 -0.5)
			(stroke
				(width 0.1)
				(type solid)
			)
			(layer "B.CrtYd")
		)
		(fp_line
			(start -0.95 0.5)
			(end 0.95 0.5)
			(stroke
				(width 0.1)
				(type solid)
			)
			(layer "B.CrtYd")
		)
		(fp_line
			(start 0.95 0.5)
			(end 0.95 -0.5)
			(stroke
				(width 0.1)
				(type solid)
			)
			(layer "B.CrtYd")
		)
		(fp_line
			(start -0.5 -0.25)
			(end 0.5 -0.25)
			(stroke
				(width 0.05)
				(type solid)
			)
			(layer "B.Fab")
		)
		(fp_line
			(start -0.5 0.25)
			(end -0.5 -0.25)
			(stroke
				(width 0.05)
				(type solid)
			)
			(layer "B.Fab")
		)
		(fp_line
			(start -0.5 0.25)
			(end 0.5 0.25)
			(stroke
				(width 0.05)
				(type solid)
			)
			(layer "B.Fab")
		)
		(fp_line
			(start 0.5 0.25)
			(end 0.5 -0.25)
			(stroke
				(width 0.05)
				(type solid)
			)
			(layer "B.Fab")
		)
		(fp_text_box "${REFERENCE}"
			(start 1.14717 0.20756)
			(end -1.14713 -0.20757)
			(margins 0 0 0 0)
			(angle 180)
			(layer "B.Fab")
			(effects
				(font
					(face "Arial")
					(size 0.315 0.315)
					(thickness 0.254)
				)
				(justify top mirror)
			)
			(border no)
			(stroke
				(width 0.1)
				(type default)
			)
			(knockout no)
		)
		(pad "1" smd rect
			(at -0.46 0)
			(size 0.6 0.62)
			(layers "B.Cu" "B.Mask" "B.Paste")
			(net "+3.3V_OSC")
			(solder_mask_margin 0.05)
			(solder_paste_margin 0)
		)
		(pad "2" smd rect
			(at 0.46 0)
			(size 0.6 0.62)
			(layers "B.Cu" "B.Mask" "B.Paste")
			(net "GND")
			(solder_mask_margin 0.05)
			(solder_paste_margin 0)
		)
	)
	(footprint "Vault:FID_1p0mm"
		(layer "B.Cu")
		(at 125.776105 81.828605 180)
		(property "Reference" "Designator5"
			(at 7.084135 3.019298 0)
			(unlocked yes)
			(layer "B.SilkS")
			(hide yes)
			(effects
				(font
					(size 1.524 1.524)
					(thickness 0.254)
				)
				(justify mirror)
			)
		)
		(property "Value" "Comment"
			(at 5.07844 0.707898 0)
			(unlocked yes)
			(layer "B.SilkS")
			(hide yes)
			(effects
				(font
					(size 1.524 1.524)
					(thickness 0.254)
				)
				(justify mirror)
			)
		)
		(sheetfile ".kicad_sch")
		(duplicate_pad_numbers_are_jumpers no)
		(fp_circle
			(center 0 0)
			(end 0 1)
			(stroke
				(width 0.1)
				(type solid)
			)
			(fill no)
			(layer "B.CrtYd")
		)
		(pad "1" smd circle
			(at 0 0 90)
			(size 1 1)
			(layers "B.Cu" "B.Mask" "B.Paste")
			(solder_mask_margin 0.5)
			(solder_paste_margin -6)
			(thermal_bridge_angle 90)
		)
		(zone
			(layer "B.Cu")
			(hatch edge 0.5)
			(connect_pads
				(clearance 0)
			)
			(min_thickness 0.25)
			(keepout
				(tracks not_allowed)
				(vias not_allowed)
				(pads allowed)
				(copperpour not_allowed)
				(footprints allowed)
			)
			(placement
				(enabled no)
				(sheetname "")
			)
			(fill
				(thermal_gap 0.5)
				(thermal_bridge_width 0.5)
				(island_removal_mode 0)
			)
			(polygon
				(pts
					(xy 126.06639 80.871665) (xy 126.247502 80.946684) (xy 126.410498 81.055595) (xy 126.549115 81.194212)
					(xy 126.658026 81.357208) (xy 126.733045 81.53832) (xy 126.77129 81.730588) (xy 126.77129 81.926622)
					(xy 126.733045 82.11889) (xy 126.658026 82.300002) (xy 126.549115 82.462998) (xy 126.410498 82.601615)
					(xy 126.247502 82.710526) (xy 126.06639 82.785545) (xy 125.874122 82.82379) (xy 125.678088 82.82379)
					(xy 125.48582 82.785545) (xy 125.304708 82.710526) (xy 125.141712 82.601615) (xy 125.003095 82.462998)
					(xy 124.894184 82.300002) (xy 124.819165 82.11889) (xy 124.78092 81.926622) (xy 124.78092 81.762779)
					(xy 125.276105 81.762779) (xy 125.276105 81.894431) (xy 125.31018 82.021598) (xy 125.376006 82.135612)
					(xy 125.469098 82.228704) (xy 125.583112 82.29453) (xy 125.710279 82.328605) (xy 125.841931 82.328605)
					(xy 125.969098 82.29453) (xy 126.083112 82.228704) (xy 126.176204 82.135612) (xy 126.24203 82.021598)
					(xy 126.276105 81.894431) (xy 126.276105 81.762779) (xy 126.24203 81.635612) (xy 126.176204 81.521598)
					(xy 126.083112 81.428506) (xy 125.969098 81.36268) (xy 125.841931 81.328605) (xy 125.710279 81.328605)
					(xy 125.583112 81.36268) (xy 125.469098 81.428506) (xy 125.376006 81.521598) (xy 125.31018 81.635612)
					(xy 125.276105 81.762779) (xy 124.78092 81.762779) (xy 124.78092 81.730588) (xy 124.819165 81.53832)
					(xy 124.894184 81.357208) (xy 125.003095 81.194212) (xy 125.141712 81.055595) (xy 125.304708 80.946684)
					(xy 125.48582 80.871665) (xy 125.678088 80.83342) (xy 125.874122 80.83342)
				)
			)
		)
	)
	(footprint "Vault:TH000V_300DIAx400_001mt_9774040243R"
		(locked yes)
		(layer "B.Cu")
		(at 148.401105 83.203605 180)
		(property "Reference" "J2"
			(at -0.00185 -3.59429 0)
			(unlocked yes)
			(layer "B.SilkS")
			(effects
				(font
					(face "Arial")
					(size 0.63 0.63)
					(thickness 0.254)
				)
				(justify mirror)
			)
		)
		(property "Value" "Wurth_9774040243R"
			(at 9.66063 -4.57418 0)
			(unlocked yes)
			(layer "B.SilkS")
			(hide yes)
			(effects
				(font
					(face "Arial")
					(size 0.63 0.63)
					(thickness 0.254)
				)
				(justify mirror)
			)
		)
		(sheetname "SCH_SA45_DaughterCard")
		(sheetfile "SCH_SA45_DaughterCard.kicad_sch")
		(duplicate_pad_numbers_are_jumpers no)
		(fp_line
			(start 3.1 3.1)
			(end -3.1 3.1)
			(stroke
				(width 0.1)
				(type solid)
			)
			(layer "B.CrtYd")
		)
		(fp_line
			(start 3.1 -3.1)
			(end 3.1 3.1)
			(stroke
				(width 0.1)
				(type solid)
			)
			(layer "B.CrtYd")
		)
		(fp_line
			(start 3.1 -3.1)
			(end -3.1 -3.1)
			(stroke
				(width 0.1)
				(type solid)
			)
			(layer "B.CrtYd")
		)
		(fp_line
			(start -3.1 -3.1)
			(end -3.1 3.1)
			(stroke
				(width 0.1)
				(type solid)
			)
			(layer "B.CrtYd")
		)
		(fp_circle
			(center 0 0)
			(end 0 1.5)
			(stroke
				(width 0.1)
				(type solid)
			)
			(fill no)
			(layer "B.Fab")
		)
		(fp_text user "${REFERENCE}"
			(at -0.002345 0.166251 360)
			(unlocked yes)
			(layer "B.Fab")
			(effects
				(font
					(face "Arial")
					(size 0.8001 0.8001)
					(thickness 0.254)
				)
				(justify mirror)
			)
		)
		(pad "" np_thru_hole circle
			(at 0 0 180)
			(size 5.3 5.3)
			(drill 3)
			(layers "*.Cu" "*.Mask")
			(solder_mask_margin 0.2)
			(solder_paste_margin -2147.48364)
			(thermal_bridge_angle 90)
		)
	)
)
